# Altium SchDoc records: 02-M2_GoldFingers.SchDoc
|HEADER=Protel for Windows - Schematic Capture Binary File Version 5.0|Weight=446|MinorVersion=9
|RECORD=31|FontIdCount=2|Size1=10|FontName1=Times New Roman|Size2=10|Rotation2=90|FontName2=Times New Roman|UseMBCS=T|IsBOC=T|HotSpotGridOn=T|HotSpotGridSize=4|SheetStyle=6|SystemFont=1|BorderOn=T|TitleBlockOn=T|SheetNumberSpaceSize=12|AreaColor=16317695|SnapGridOn=T|SnapGridSize=10|VisibleGridOn=T|VisibleGridSize=10|CustomX=1500|CustomY=950|CustomXZones=6|CustomYZones=4|CustomMarginWidth=20|Display_Unit=0
|RECORD=41|OwnerPartId=-1|Color=8388608|FontID=1|IsHidden=T|Text=*|Name=CurrentTime|ReadOnlyState=1
|RECORD=41|IndexInSheet=1|OwnerPartId=-1|Color=8388608|FontID=1|IsHidden=T|Text=*|Name=CurrentDate|ReadOnlyState=1
|RECORD=41|IndexInSheet=2|OwnerPartId=-1|Color=8388608|FontID=1|IsHidden=T|Text=*|Name=Time|ReadOnlyState=1
|RECORD=41|IndexInSheet=3|OwnerPartId=-1|Color=8388608|FontID=1|IsHidden=T|Text=*|Name=Date|ReadOnlyState=1
|RECORD=41|IndexInSheet=4|OwnerPartId=-1|Color=8388608|FontID=1|IsHidden=T|Text=*|Name=DocumentFullPathAndName|ReadOnlyState=1
|RECORD=41|IndexInSheet=5|OwnerPartId=-1|Color=8388608|FontID=1|IsHidden=T|Text=*|Name=DocumentName|ReadOnlyState=1
|RECORD=41|IndexInSheet=6|OwnerPartId=-1|Color=8388608|FontID=1|IsHidden=T|Text=*|Name=ModifiedDate|ReadOnlyState=1
|RECORD=41|IndexInSheet=7|OwnerPartId=-1|Color=8388608|FontID=1|IsHidden=T|Text=*|Name=ApprovedBy|ReadOnlyState=1
|RECORD=41|IndexInSheet=8|OwnerPartId=-1|Color=8388608|FontID=1|IsHidden=T|Text=*|Name=CheckedBy|ReadOnlyState=1
|RECORD=41|IndexInSheet=9|OwnerPartId=-1|Color=8388608|FontID=1|IsHidden=T|Text=*|Name=Author|ReadOnlyState=1
|RECORD=41|IndexInSheet=10|OwnerPartId=-1|Color=8388608|FontID=1|IsHidden=T|Text=*|Name=CompanyName|ReadOnlyState=1
|RECORD=41|IndexInSheet=11|OwnerPartId=-1|Color=8388608|FontID=1|IsHidden=T|Text=*|Name=DrawnBy|ReadOnlyState=1
|RECORD=41|IndexInSheet=12|OwnerPartId=-1|Color=8388608|FontID=1|IsHidden=T|Text=*|Name=Engineer|ReadOnlyState=1
|RECORD=41|IndexInSheet=13|OwnerPartId=-1|Color=8388608|FontID=1|IsHidden=T|Text=*|Name=Organization|ReadOnlyState=1
|RECORD=41|IndexInSheet=14|OwnerPartId=-1|Color=8388608|FontID=1|IsHidden=T|Text=*|Name=Address1|ReadOnlyState=1
|RECORD=41|IndexInSheet=15|OwnerPartId=-1|Color=8388608|FontID=1|IsHidden=T|Text=*|Name=Address2|ReadOnlyState=1
|RECORD=41|IndexInSheet=16|OwnerPartId=-1|Color=8388608|FontID=1|IsHidden=T|Text=*|Name=Address3|ReadOnlyState=1
|RECORD=41|IndexInSheet=17|OwnerPartId=-1|Color=8388608|FontID=1|IsHidden=T|Text=*|Name=Address4|ReadOnlyState=1
|RECORD=41|IndexInSheet=18|OwnerPartId=-1|Color=8388608|FontID=1|IsHidden=T|Text=*|Name=Title|ReadOnlyState=1
|RECORD=41|IndexInSheet=19|OwnerPartId=-1|Color=8388608|FontID=1|IsHidden=T|Text=*|Name=DocumentNumber|ReadOnlyState=1
|RECORD=41|IndexInSheet=20|OwnerPartId=-1|Color=8388608|FontID=1|IsHidden=T|Text=*|Name=Revision|ReadOnlyState=1
|RECORD=41|IndexInSheet=21|OwnerPartId=-1|Color=8388608|FontID=1|IsHidden=T|Text=2|Name=SheetNumber|ReadOnlyState=1
|RECORD=41|IndexInSheet=22|OwnerPartId=-1|Color=8388608|FontID=1|IsHidden=T|Text=2|Name=SheetTotal|ReadOnlyState=1
|RECORD=41|IndexInSheet=23|OwnerPartId=-1|Color=8388608|FontID=1|IsHidden=T|Text=*|Name=Rule|ReadOnlyState=1
|RECORD=41|IndexInSheet=24|OwnerPartId=-1|Color=8388608|FontID=1|IsHidden=T|Text=*|Name=ImagePath|ReadOnlyState=1
|RECORD=41|IndexInSheet=25|OwnerPartId=-1|Color=8388608|FontID=1|IsHidden=T|Text=*|Name=ProjectName|ReadOnlyState=1
|RECORD=41|IndexInSheet=26|OwnerPartId=-1|Color=8388608|FontID=1|IsHidden=T|Text=*|Name=Application_BuildNumber|ReadOnlyState=1
|RECORD=1|LibReference=OCPTAP_M2_FINGERS|PartCount=2|DisplayModeCount=1|IndexInSheet=27|OwnerPartId=-1|Location.X=680|Location.Y=630|CurrentPartId=1|LibraryPath=*|SourceLibraryName=M2_Library.SchLib|TargetFileName=*|AreaColor=11599871|Color=128|PartIDLocked=T|NotUseDBTableName=T|DesignItemId=OCPTAP_M2_FINGERS|AllPinCount=67|ComponentKindVersion2=5
|RECORD=14|OwnerIndex=28|IsNotAccesible=T|OwnerPartId=1|Location.X=710|Location.Y=250|Corner.X=860|Corner.Y=720|Color=128|AreaColor=11599871|IsSolid=T
|RECORD=2|OwnerIndex=28|OwnerPartId=1|FormalType=1|PinConglomerate=58|PinLength=30|Location.X=710|Location.Y=710|Name=V3P3_1|Designator=2|SwapIDPart=Ž&Ž||PinPropagationDelay=0.000000E+000
|RECORD=2|OwnerIndex=28|OwnerPartId=1|FormalType=1|PinConglomerate=58|PinLength=30|Location.X=710|Location.Y=700|Name=V3P3_2|Designator=4|SwapIDPart=Ž&Ž||PinPropagationDelay=0.000000E+000
|RECORD=2|OwnerIndex=28|OwnerPartId=1|FormalType=1|PinConglomerate=58|PinLength=30|Location.X=710|Location.Y=620|Name=SMCLK|Designator=40|SwapIDPart=Ž&Ž||PinPropagationDelay=0.000000E+000
|RECORD=2|OwnerIndex=28|OwnerPartId=1|FormalType=1|PinConglomerate=58|PinLength=30|Location.X=710|Location.Y=610|Name=SMDAT|Designator=42|SwapIDPart=Ž&Ž||PinPropagationDelay=0.000000E+000
|RECORD=2|OwnerIndex=28|OwnerPartId=1|FormalType=1|PinConglomerate=58|PinLength=30|Location.X=710|Location.Y=600|Name=ALERT_L|Designator=44|SwapIDPart=Ž&Ž||PinPropagationDelay=0.000000E+000
|RECORD=2|OwnerIndex=28|OwnerPartId=1|FormalType=1|PinConglomerate=58|PinLength=30|Location.X=710|Location.Y=640|Name=PERST_L|Designator=50|SwapIDPart=Ž&Ž||PinPropagationDelay=0.000000E+000
|RECORD=2|OwnerIndex=28|OwnerPartId=1|FormalType=1|PinConglomerate=56|PinLength=30|Location.X=860|Location.Y=390|Name=NC|Designator=52|SwapIDPart=Ž&Ž||PinPropagationDelay=0.000000E+000
|RECORD=2|OwnerIndex=28|OwnerPartId=1|FormalType=1|PinConglomerate=56|PinLength=30|Location.X=860|Location.Y=370|Name=NC|Designator=54|SwapIDPart=Ž&Ž||PinPropagationDelay=0.000000E+000
|RECORD=2|OwnerIndex=28|OwnerPartId=1|FormalType=1|PinConglomerate=56|PinLength=30|Location.X=860|Location.Y=630|Name=PPS_OUT_OPT|Designator=35|SwapIDPart=Ž&Ž||PinPropagationDelay=0.000000E+000
|RECORD=2|OwnerIndex=28|OwnerPartId=1|FormalType=1|PinConglomerate=58|PinLength=30|Location.X=710|Location.Y=430|Name=GND|Designator=3|SwapIDPart=Ž&Ž||PinPropagationDelay=0.000000E+000
|RECORD=2|OwnerIndex=28|OwnerPartId=1|FormalType=1|PinConglomerate=58|PinLength=30|Location.X=710|Location.Y=420|Name=GND|Designator=5|SwapIDPart=Ž&Ž||PinPropagationDelay=0.000000E+000
|RECORD=2|OwnerIndex=28|OwnerPartId=1|FormalType=1|PinConglomerate=58|PinLength=30|Location.X=710|Location.Y=410|Name=GND|Designator=11|SwapIDPart=Ž&Ž||PinPropagationDelay=0.000000E+000
|RECORD=2|OwnerIndex=28|OwnerPartId=1|FormalType=1|PinConglomerate=58|PinLength=30|Location.X=710|Location.Y=530|Name=CONFIG_0(GND)|Designator=21|SwapIDPart=Ž&Ž||PinPropagationDelay=0.000000E+000
|RECORD=2|OwnerIndex=28|OwnerPartId=1|FormalType=1|PinConglomerate=58|PinLength=30|Location.X=710|Location.Y=400|Name=GND|Designator=27|SwapIDPart=Ž&Ž||PinPropagationDelay=0.000000E+000
|RECORD=2|OwnerIndex=28|OwnerPartId=1|FormalType=1|PinConglomerate=58|PinLength=30|Location.X=710|Location.Y=390|Name=GND|Designator=33|SwapIDPart=Ž&Ž||PinPropagationDelay=0.000000E+000
|RECORD=2|OwnerIndex=28|OwnerPartId=1|FormalType=1|PinConglomerate=58|PinLength=30|Location.X=710|Location.Y=380|Name=GND|Designator=39|SwapIDPart=Ž&Ž||PinPropagationDelay=0.000000E+000
|RECORD=2|OwnerIndex=28|OwnerPartId=1|FormalType=1|PinConglomerate=58|PinLength=30|Location.X=710|Location.Y=370|Name=GND|Designator=45|SwapIDPart=Ž&Ž||PinPropagationDelay=0.000000E+000
|RECORD=2|OwnerIndex=28|OwnerPartId=1|FormalType=1|PinConglomerate=58|PinLength=30|Location.X=710|Location.Y=360|Name=GND|Designator=51|SwapIDPart=Ž&Ž||PinPropagationDelay=0.000000E+000
|RECORD=2|OwnerIndex=28|OwnerPartId=1|FormalType=1|PinConglomerate=58|PinLength=30|Location.X=710|Location.Y=350|Name=GND|Designator=57|SwapIDPart=Ž&Ž||PinPropagationDelay=0.000000E+000
|RECORD=2|OwnerIndex=28|OwnerPartId=1|FormalType=1|PinConglomerate=58|PinLength=30|Location.X=710|Location.Y=340|Name=GND|Designator=71|SwapIDPart=Ž&Ž||PinPropagationDelay=0.000000E+000
|RECORD=2|OwnerIndex=28|OwnerPartId=1|FormalType=1|PinConglomerate=58|PinLength=30|Location.X=710|Location.Y=490|Name=VIO_CFG(GND)|Designator=73|SwapIDPart=Ž&Ž||PinPropagationDelay=0.000000E+000
|RECORD=2|OwnerIndex=28|OwnerPartId=1|FormalType=1|PinConglomerate=58|PinLength=30|Location.X=710|Location.Y=510|Name=CONFIG_2(GND)|Designator=75|SwapIDPart=Ž&Ž||PinPropagationDelay=0.000000E+000
|RECORD=2|OwnerIndex=28|OwnerPartId=1|FormalType=1|PinConglomerate=58|PinLength=30|Location.X=710|Location.Y=670|Name=V3P3_7|Designator=70|SwapIDPart=Ž&Ž||PinPropagationDelay=0.000000E+000
|RECORD=2|OwnerIndex=28|OwnerPartId=1|FormalType=1|PinConglomerate=58|PinLength=30|Location.X=710|Location.Y=680|Name=V3P3_8|Designator=72|SwapIDPart=Ž&Ž||PinPropagationDelay=0.000000E+000
|RECORD=2|OwnerIndex=28|OwnerPartId=1|FormalType=1|PinConglomerate=58|PinLength=30|Location.X=710|Location.Y=690|Name=V3P3_9|Designator=74|SwapIDPart=Ž&Ž||PinPropagationDelay=0.000000E+000
|RECORD=2|OwnerIndex=28|OwnerPartId=1|FormalType=1|PinConglomerate=56|PinLength=30|Location.X=860|Location.Y=690|Name=LED1_L|Designator=10|SwapIDPart=Ž&Ž||PinPropagationDelay=0.000000E+000
|RECORD=2|OwnerIndex=28|OwnerPartId=1|FormalType=1|PinConglomerate=56|PinLength=30|Location.X=860|Location.Y=350|Name=NC|Designator=56|SwapIDPart=Ž&Ž||PinPropagationDelay=0.000000E+000
|RECORD=2|OwnerIndex=28|OwnerPartId=1|FormalType=1|PinConglomerate=56|PinLength=30|Location.X=860|Location.Y=340|Name=NC|Designator=58|SwapIDPart=Ž&Ž||PinPropagationDelay=0.000000E+000
|RECORD=2|OwnerIndex=28|OwnerPartId=1|FormalType=1|Electrical=2|PinConglomerate=56|PinLength=30|Location.X=860|Location.Y=600|Name=UARTIN_RX|Designator=62|SwapIDPart=Ž&Ž||PinPropagationDelay=0.000000E+000
|RECORD=2|OwnerIndex=28|OwnerPartId=1|FormalType=1|Electrical=2|PinConglomerate=56|PinLength=30|Location.X=860|Location.Y=710|Name=PWR_OFF|Designator=6|SwapIDPart=Ž&Ž||PinPropagationDelay=0.000000E+000
|RECORD=2|OwnerIndex=28|OwnerPartId=1|FormalType=1|Electrical=2|PinConglomerate=56|PinLength=30|Location.X=860|Location.Y=700|Name=W_DISABLE#|Designator=8|SwapIDPart=Ž&Ž||PinPropagationDelay=0.000000E+000
|RECORD=2|OwnerIndex=28|OwnerPartId=1|FormalType=1|Electrical=2|PinConglomerate=56|PinLength=30|Location.X=860|Location.Y=660|Name=10MHZ_IN|Designator=20|SwapIDPart=Ž&Ž||PinPropagationDelay=0.000000E+000
|RECORD=2|OwnerIndex=28|OwnerPartId=1|FormalType=1|Electrical=2|PinConglomerate=56|PinLength=30|Location.X=860|Location.Y=650|Name=PPS_IN|Designator=22|SwapIDPart=Ž&Ž||PinPropagationDelay=0.000000E+000
|RECORD=2|OwnerIndex=28|OwnerPartId=1|FormalType=1|PinConglomerate=56|PinLength=30|Location.X=860|Location.Y=550|Name=NC|Designator=24|SwapIDPart=Ž&Ž||PinPropagationDelay=0.000000E+000
|RECORD=2|OwnerIndex=28|OwnerPartId=1|FormalType=1|PinConglomerate=56|PinLength=30|Location.X=860|Location.Y=530|Name=NC|Designator=26|SwapIDPart=Ž&Ž||PinPropagationDelay=0.000000E+000
|RECORD=2|OwnerIndex=28|OwnerPartId=1|FormalType=1|PinConglomerate=56|PinLength=30|Location.X=860|Location.Y=520|Name=NC|Designator=28|SwapIDPart=Ž&Ž||PinPropagationDelay=0.000000E+000
|RECORD=2|OwnerIndex=28|OwnerPartId=1|FormalType=1|PinConglomerate=56|PinLength=30|Location.X=860|Location.Y=500|Name=NC|Designator=30|SwapIDPart=Ž&Ž||PinPropagationDelay=0.000000E+000
|RECORD=2|OwnerIndex=28|OwnerPartId=1|FormalType=1|PinConglomerate=56|PinLength=30|Location.X=860|Location.Y=480|Name=NC|Designator=32|SwapIDPart=Ž&Ž||PinPropagationDelay=0.000000E+000
|RECORD=2|OwnerIndex=28|OwnerPartId=1|FormalType=1|PinConglomerate=56|PinLength=30|Location.X=860|Location.Y=470|Name=NC|Designator=34|SwapIDPart=Ž&Ž||PinPropagationDelay=0.000000E+000
|RECORD=2|OwnerIndex=28|OwnerPartId=1|FormalType=1|PinConglomerate=56|PinLength=30|Location.X=860|Location.Y=460|Name=NC|Designator=36|SwapIDPart=Ž&Ž||PinPropagationDelay=0.000000E+000
|RECORD=2|OwnerIndex=28|OwnerPartId=1|FormalType=1|PinConglomerate=56|PinLength=30|Location.X=860|Location.Y=440|Name=NC|Designator=38|SwapIDPart=Ž&Ž||PinPropagationDelay=0.000000E+000
|RECORD=2|OwnerIndex=28|OwnerPartId=1|FormalType=1|PinConglomerate=56|PinLength=30|Location.X=860|Location.Y=620|Name=PPS_OUT|Designator=46|SwapIDPart=Ž&Ž||PinPropagationDelay=0.000000E+000
|RECORD=2|OwnerIndex=28|OwnerPartId=1|FormalType=1|PinConglomerate=56|PinLength=30|Location.X=860|Location.Y=640|Name=10MHZ_OUT|Designator=48|SwapIDPart=Ž&Ž||PinPropagationDelay=0.000000E+000
|RECORD=2|OwnerIndex=28|OwnerPartId=1|FormalType=1|PinConglomerate=56|PinLength=30|Location.X=860|Location.Y=280|Name=NC|Designator=66|SwapIDPart=Ž&Ž||PinPropagationDelay=0.000000E+000
|RECORD=2|OwnerIndex=28|OwnerPartId=1|FormalType=1|PinConglomerate=56|PinLength=30|Location.X=860|Location.Y=320|Name=NC|Designator=60|SwapIDPart=Ž&Ž||PinPropagationDelay=0.000000E+000
|RECORD=2|OwnerIndex=28|OwnerPartId=1|FormalType=1|PinConglomerate=56|PinLength=30|Location.X=860|Location.Y=590|Name=UARTOUT_TX|Designator=64|SwapIDPart=Ž&Ž||PinPropagationDelay=0.000000E+000
|RECORD=2|OwnerIndex=28|OwnerPartId=1|FormalType=1|PinConglomerate=56|PinLength=30|Location.X=860|Location.Y=270|Name=NC|Designator=68|SwapIDPart=Ž&Ž||PinPropagationDelay=0.000000E+000
|RECORD=2|OwnerIndex=28|OwnerPartId=1|FormalType=1|PinConglomerate=58|PinLength=30|Location.X=710|Location.Y=500|Name=CONFIG_3(NC)|Designator=1|SwapIDPart=Ž&Ž||PinPropagationDelay=0.000000E+000
|RECORD=2|OwnerIndex=28|OwnerPartId=1|FormalType=1|PinConglomerate=58|PinLength=30|Location.X=710|Location.Y=570|Name=USB_DP|Designator=7|SwapIDPart=Ž&Ž||PinPropagationDelay=0.000000E+000
|RECORD=2|OwnerIndex=28|OwnerPartId=1|FormalType=1|PinConglomerate=58|PinLength=30|Location.X=710|Location.Y=560|Name=USB_DN|Designator=9|SwapIDPart=Ž&Ž||PinPropagationDelay=0.000000E+000
|RECORD=2|OwnerIndex=28|OwnerPartId=1|FormalType=1|PinConglomerate=56|PinLength=30|Location.X=860|Location.Y=560|Name=NC|Designator=23|SwapIDPart=Ž&Ž||PinPropagationDelay=0.000000E+000
|RECORD=2|OwnerIndex=28|OwnerPartId=1|FormalType=1|PinConglomerate=56|PinLength=30|Location.X=860|Location.Y=540|Name=NC|Designator=25|SwapIDPart=Ž&Ž||PinPropagationDelay=0.000000E+000
|RECORD=2|OwnerIndex=28|OwnerPartId=1|FormalType=1|PinConglomerate=56|PinLength=30|Location.X=860|Location.Y=510|Name=NC|Designator=29|SwapIDPart=Ž&Ž||PinPropagationDelay=0.000000E+000
|RECORD=2|OwnerIndex=28|OwnerPartId=1|FormalType=1|PinConglomerate=56|PinLength=30|Location.X=860|Location.Y=490|Name=NC|Designator=31|SwapIDPart=Ž&Ž||PinPropagationDelay=0.000000E+000
|RECORD=2|OwnerIndex=28|OwnerPartId=1|FormalType=1|PinConglomerate=56|PinLength=30|Location.X=860|Location.Y=450|Name=NC|Designator=37|SwapIDPart=Ž&Ž||PinPropagationDelay=0.000000E+000
|RECORD=2|OwnerIndex=28|OwnerPartId=1|FormalType=1|PinConglomerate=56|PinLength=30|Location.X=860|Location.Y=430|Name=NC|Designator=41|SwapIDPart=Ž&Ž||PinPropagationDelay=0.000000E+000
|RECORD=2|OwnerIndex=28|OwnerPartId=1|FormalType=1|PinConglomerate=56|PinLength=30|Location.X=860|Location.Y=420|Name=NC|Designator=43|SwapIDPart=Ž&Ž||PinPropagationDelay=0.000000E+000
|RECORD=2|OwnerIndex=28|OwnerPartId=1|FormalType=1|PinConglomerate=56|PinLength=30|Location.X=860|Location.Y=410|Name=NC|Designator=47|SwapIDPart=Ž&Ž||PinPropagationDelay=0.000000E+000
|RECORD=2|OwnerIndex=28|OwnerPartId=1|FormalType=1|PinConglomerate=56|PinLength=30|Location.X=860|Location.Y=400|Name=NC|Designator=49|SwapIDPart=Ž&Ž||PinPropagationDelay=0.000000E+000
|RECORD=2|OwnerIndex=28|OwnerPartId=1|FormalType=1|PinConglomerate=56|PinLength=30|Location.X=860|Location.Y=380|Name=NC|Designator=53|SwapIDPart=Ž&Ž||PinPropagationDelay=0.000000E+000
|RECORD=2|OwnerIndex=28|OwnerPartId=1|FormalType=1|PinConglomerate=56|PinLength=30|Location.X=860|Location.Y=360|Name=NC|Designator=55|SwapIDPart=Ž&Ž||PinPropagationDelay=0.000000E+000
|RECORD=2|OwnerIndex=28|OwnerPartId=1|FormalType=1|PinConglomerate=56|PinLength=30|Location.X=860|Location.Y=330|Name=NC|Designator=59|SwapIDPart=Ž&Ž||PinPropagationDelay=0.000000E+000
|RECORD=2|OwnerIndex=28|OwnerPartId=1|FormalType=1|PinConglomerate=56|PinLength=30|Location.X=860|Location.Y=310|Name=NC|Designator=61|SwapIDPart=Ž&Ž||PinPropagationDelay=0.000000E+000
|RECORD=2|OwnerIndex=28|OwnerPartId=1|FormalType=1|PinConglomerate=56|PinLength=30|Location.X=860|Location.Y=300|Name=NC|Designator=63|SwapIDPart=Ž&Ž||PinPropagationDelay=0.000000E+000
|RECORD=2|OwnerIndex=28|OwnerPartId=1|FormalType=1|PinConglomerate=56|PinLength=30|Location.X=860|Location.Y=290|Name=NC|Designator=65|SwapIDPart=Ž&Ž||PinPropagationDelay=0.000000E+000
|RECORD=2|OwnerIndex=28|OwnerPartId=1|FormalType=1|PinConglomerate=58|PinLength=30|Location.X=710|Location.Y=650|Name=RESET_L|Designator=67|SwapIDPart=Ž&Ž||PinPropagationDelay=0.000000E+000
|RECORD=2|OwnerIndex=28|OwnerPartId=1|FormalType=1|PinConglomerate=58|PinLength=30|Location.X=710|Location.Y=520|Name=CONFIG_1(NC)|Designator=69|SwapIDPart=Ž&Ž||PinPropagationDelay=0.000000E+000
|RECORD=34|OwnerIndex=28|IndexInSheet=-1|OwnerPartId=-1|Location.X=710|Location.Y=720|Color=8388608|FontID=1|Text=J1|Name=Designator|ReadOnlyState=1
|RECORD=41|OwnerIndex=28|IndexInSheet=-1|OwnerPartId=-1|Location.X=710|Location.Y=240|Color=8388608|FontID=1|Text=OCPTAP_M2_FINGERS|Name=Comment
|RECORD=44|OwnerIndex=28
|RECORD=45|OwnerIndex=166|IndexInSheet=-1|ModelName=OCPTAP M2 FINGERS|ModelType=PCBLIB|DatafileCount=1|ModelDatafileEntity0=OCPTAP M2 FINGERS|ModelDatafileKind0=PCBLib|IsCurrent=T
|RECORD=46|OwnerIndex=167
|RECORD=48|OwnerIndex=167
|RECORD=17|IndexInSheet=28|OwnerPartId=-1|Style=4|ShowNetName=F|Location.X=660|Location.Y=320|Orientation=3|Color=128|FontID=1|Text=GND
|RECORD=27|IndexInSheet=29|OwnerPartId=-1|LineWidth=1|Color=8388608|LocationCount=12|X1=680|Y1=430|X2=660|Y2=430|X3=660|Y3=420|X4=660|Y4=410|X5=660|Y5=400|X6=660|Y6=390|X7=660|Y7=380|X8=660|Y8=370|X9=660|Y9=360|X10=660|Y10=350|X11=660|Y11=340|X12=660|Y12=320
|RECORD=27|IndexInSheet=30|OwnerPartId=-1|LineWidth=1|Color=8388608|LocationCount=2|X1=680|Y1=340|X2=660|Y2=340
|RECORD=27|IndexInSheet=31|OwnerPartId=-1|LineWidth=1|Color=8388608|LocationCount=2|X1=680|Y1=350|X2=660|Y2=350
|RECORD=27|IndexInSheet=32|OwnerPartId=-1|LineWidth=1|Color=8388608|LocationCount=2|X1=680|Y1=360|X2=660|Y2=360
|RECORD=27|IndexInSheet=33|OwnerPartId=-1|LineWidth=1|Color=8388608|LocationCount=2|X1=680|Y1=370|X2=660|Y2=370
|RECORD=27|IndexInSheet=34|OwnerPartId=-1|LineWidth=1|Color=8388608|LocationCount=2|X1=680|Y1=380|X2=660|Y2=380
|RECORD=27|IndexInSheet=35|OwnerPartId=-1|LineWidth=1|Color=8388608|LocationCount=2|X1=680|Y1=390|X2=660|Y2=390
|RECORD=27|IndexInSheet=36|OwnerPartId=-1|LineWidth=1|Color=8388608|LocationCount=2|X1=680|Y1=400|X2=660|Y2=400
|RECORD=27|IndexInSheet=37|OwnerPartId=-1|LineWidth=1|Color=8388608|LocationCount=2|X1=680|Y1=410|X2=660|Y2=410
|RECORD=27|IndexInSheet=38|OwnerPartId=-1|LineWidth=1|Color=8388608|LocationCount=2|X1=680|Y1=420|X2=660|Y2=420
|RECORD=27|IndexInSheet=39|OwnerPartId=-1|LineWidth=1|Color=8388608|LocationCount=5|X1=680|Y1=530|X2=660|Y2=530|X3=660|Y3=510|X4=660|Y4=490|X5=660|Y5=430
|RECORD=27|IndexInSheet=40|OwnerPartId=-1|LineWidth=1|Color=8388608|LocationCount=2|X1=680|Y1=510|X2=660|Y2=510
|RECORD=27|IndexInSheet=41|OwnerPartId=-1|LineWidth=1|Color=8388608|LocationCount=2|X1=680|Y1=490|X2=660|Y2=490
|RECORD=17|IndexInSheet=42|OwnerPartId=-1|Style=2|ShowNetName=T|Location.X=660|Location.Y=770|Orientation=1|Color=128|FontID=1|Text=+3V3
|RECORD=27|IndexInSheet=43|OwnerPartId=-1|LineWidth=1|Color=8388608|LocationCount=2|X1=680|Y1=710|X2=660|Y2=710
|RECORD=27|IndexInSheet=44|OwnerPartId=-1|LineWidth=1|Color=8388608|LocationCount=2|X1=680|Y1=700|X2=660|Y2=700
|RECORD=27|IndexInSheet=45|OwnerPartId=-1|LineWidth=1|Color=8388608|LocationCount=2|X1=680|Y1=690|X2=660|Y2=690
|RECORD=27|IndexInSheet=46|OwnerPartId=-1|LineWidth=1|Color=8388608|LocationCount=2|X1=680|Y1=680|X2=660|Y2=680
|RECORD=17|IndexInSheet=47|OwnerPartId=-1|Style=1|ShowNetName=T|Location.X=540|Location.Y=650|Orientation=2|Color=255|FontID=1|Text=RST_GPS|IsCrossSheetConnector=T
|RECORD=17|IndexInSheet=48|OwnerPartId=-1|Style=1|ShowNetName=T|Location.X=930|Location.Y=600|Color=255|FontID=1|Text=RX_GPS_CONN|IsCrossSheetConnector=T
|RECORD=17|IndexInSheet=49|OwnerPartId=-1|ShowNetName=T|Location.X=930|Location.Y=590|Color=255|FontID=1|Text=TX_GPS_CONN|IsCrossSheetConnector=T
|RECORD=27|IndexInSheet=50|OwnerPartId=-1|LineWidth=1|Color=8388608|LocationCount=2|X1=890|Y1=600|X2=930|Y2=600
|RECORD=27|IndexInSheet=51|OwnerPartId=-1|LineWidth=1|Color=8388608|LocationCount=2|X1=890|Y1=590|X2=930|Y2=590
|RECORD=17|IndexInSheet=52|OwnerPartId=-1|ShowNetName=T|Location.X=640|Location.Y=570|Orientation=2|Color=255|FontID=1|Text=USB_DP|IsCrossSheetConnector=T
|RECORD=17|IndexInSheet=53|OwnerPartId=-1|ShowNetName=T|Location.X=640|Location.Y=560|Orientation=2|Color=255|FontID=1|Text=USB_DM|IsCrossSheetConnector=T
|RECORD=27|IndexInSheet=54|OwnerPartId=-1|LineWidth=1|Color=8388608|LocationCount=2|X1=640|Y1=560|X2=680|Y2=560
|RECORD=27|IndexInSheet=55|OwnerPartId=-1|LineWidth=1|Color=8388608|LocationCount=2|X1=640|Y1=570|X2=680|Y2=570
|RECORD=17|IndexInSheet=56|OwnerPartId=-1|ShowNetName=T|Location.X=600|Location.Y=610|Orientation=2|Color=255|FontID=1|Text=SDA|IsCrossSheetConnector=T
|RECORD=17|IndexInSheet=57|OwnerPartId=-1|ShowNetName=T|Location.X=600|Location.Y=620|Orientation=2|Color=255|FontID=1|Text=SCL|IsCrossSheetConnector=T
|RECORD=27|IndexInSheet=58|OwnerPartId=-1|LineWidth=1|Color=8388608|LocationCount=2|X1=600|Y1=610|X2=680|Y2=610
|RECORD=27|IndexInSheet=59|OwnerPartId=-1|LineWidth=1|Color=8388608|LocationCount=2|X1=600|Y1=620|X2=680|Y2=620
|RECORD=27|IndexInSheet=60|OwnerPartId=-1|LineWidth=1|Color=8388608|LocationCount=2|X1=680|Y1=640|X2=610|Y2=640
|RECORD=27|IndexInSheet=61|OwnerPartId=-1|LineWidth=1|Color=8388608|LocationCount=4|X1=680|Y1=650|X2=630|Y2=650|X3=630|Y3=670|X4=610|Y4=670
|RECORD=27|IndexInSheet=62|OwnerPartId=-1|LineWidth=1|Color=8388608|LocationCount=4|X1=570|Y1=670|X2=560|Y2=670|X3=560|Y3=650|X4=540|Y4=650
|RECORD=27|IndexInSheet=63|OwnerPartId=-1|LineWidth=1|Color=8388608|LocationCount=3|X1=570|Y1=640|X2=560|Y2=640|X3=560|Y3=650
|RECORD=1|LibReference=02cd4be3c70576c341d710602a673aa|ComponentDescription=Chip Multilayer Ceramic Capacitors for General Purpose, 1206, 47uF, X5R, 15%, 20%, 6.3V|PartCount=2|DisplayModeCount=1|IndexInSheet=64|OwnerPartId=-1|Location.X=540|Location.Y=730|CurrentPartId=1|LibraryPath=*|SourceLibraryName=Altium Content Vault|TargetFileName=*|AreaColor=11599871|Color=128|PartIDLocked=T|DesignItemId=CMP-2000-06344-2|AllPinCount=2
|RECORD=2|OwnerIndex=206|OwnerPartId=1|Electrical=4|PinConglomerate=49|PinLength=7|Location.X=540|Location.Y=723|Name=1|Designator=1|PinPropagationDelay=0.000000E+000
|RECORD=2|OwnerIndex=206|OwnerPartId=1|Electrical=4|PinConglomerate=51|PinLength=6|Location.X=540|Location.Y=716|Name=2|Designator=2|PinPropagationDelay=0.000000E+000
|RECORD=13|OwnerIndex=206|IsNotAccesible=T|IndexInSheet=2|OwnerPartId=1|Location.X=550|Location.Y=723|Corner.X=530|Corner.Y=723|LineWidth=1|Color=16711680
|RECORD=13|OwnerIndex=206|IsNotAccesible=T|IndexInSheet=3|OwnerPartId=1|Location.X=550|Location.Y=717|Corner.X=530|Corner.Y=717|LineWidth=1|Color=16711680
|RECORD=13|OwnerIndex=206|IsNotAccesible=T|IndexInSheet=4|OwnerPartId=1|Location.X=540|Location.Y=723|Corner.X=540|Corner.Y=726|LineWidth=1|Color=16711680
|RECORD=13|OwnerIndex=206|IsNotAccesible=T|IndexInSheet=5|OwnerPartId=1|Location.X=540|Location.Y=716|Corner.X=540|Corner.Y=715|LineWidth=1|Color=16711680
|RECORD=41|OwnerIndex=206|IndexInSheet=6|OwnerPartId=-1|Location.X=529|Location.Y=732|Color=8388608|FontID=1|IsHidden=T|Text=2000|Name=Package Quantity
|RECORD=41|OwnerIndex=206|IndexInSheet=7|OwnerPartId=-1|Location.X=529|Location.Y=732|Color=8388608|FontID=1|IsHidden=T|Text=Surface Mount|Name=Mount
|RECORD=41|OwnerIndex=206|IndexInSheet=8|OwnerPartId=-1|Location.X=529|Location.Y=732|Color=8388608|FontID=1|IsHidden=T|Text=3.2mm|Name=Length
|RECORD=41|OwnerIndex=206|IndexInSheet=9|OwnerPartId=-1|Location.X=529|Location.Y=732|Color=8388608|FontID=1|IsHidden=T|Text=0.071inch|Name=Thickness
|RECORD=41|OwnerIndex=206|IndexInSheet=10|OwnerPartId=-1|Location.X=529|Location.Y=732|Color=8388608|FontID=1|IsHidden=T|Text=Lead Free|Name=Lead Free
|RECORD=41|OwnerIndex=206|IndexInSheet=11|OwnerPartId=-1|Location.X=529|Location.Y=732|Color=8388608|FontID=1|IsHidden=T|Text=20%|Name=Tolerance
|RECORD=41|OwnerIndex=206|IndexInSheet=12|OwnerPartId=-1|Location.X=529|Location.Y=732|Color=8388608|FontID=1|IsHidden=T|Text=0.063inch|Name=Width
|RECORD=41|OwnerIndex=206|IndexInSheet=13|OwnerPartId=-1|Location.X=529|Location.Y=732|Color=8388608|FontID=1|IsHidden=T|Text=1.6mm|Name=Depth
|RECORD=41|OwnerIndex=206|IndexInSheet=14|OwnerPartId=-1|Location.X=529|Location.Y=732|Color=8388608|FontID=1|IsHidden=T|Text=1206|Name=Case/Package
|RECORD=41|OwnerIndex=206|IndexInSheet=15|OwnerPartId=-1|Location.X=529|Location.Y=732|Color=8388608|FontID=1|IsHidden=T|Text=X5R|Name=Dielectric
|RECORD=41|OwnerIndex=206|IndexInSheet=16|OwnerPartId=-1|Location.X=529|Location.Y=732|Color=8388608|FontID=1|IsHidden=T|Text=No|Name=Radiation Hardening
|RECORD=41|OwnerIndex=206|IndexInSheet=17|OwnerPartId=-1|Location.X=529|Location.Y=732|Color=8388608|FontID=1|IsHidden=T|Text=Tape and Reel|Name=Packaging
|RECORD=41|OwnerIndex=206|IndexInSheet=18|OwnerPartId=-1|Location.X=529|Location.Y=732|Color=8388608|FontID=1|IsHidden=T|Text=6.3V|Name=Voltage Rating (DC)
|RECORD=41|OwnerIndex=206|IndexInSheet=19|OwnerPartId=-1|Location.X=529|Location.Y=732|Color=8388608|FontID=1|IsHidden=T|Text=SMD/SMT|Name=Termination
|RECORD=41|OwnerIndex=206|IndexInSheet=20|OwnerPartId=-1|Location.X=529|Location.Y=732|Color=8388608|FontID=1|IsHidden=T|Text=1.6mm|Name=Height
|RECORD=41|OwnerIndex=206|IndexInSheet=21|OwnerPartId=-1|Location.X=529|Location.Y=732|Color=8388608|FontID=1|IsHidden=T|Text=85°C|Name=Max Operating Temperature
|RECORD=41|OwnerIndex=206|IndexInSheet=22|OwnerPartId=-1|Location.X=529|Location.Y=732|Color=8388608|FontID=1|IsHidden=T|Text=3216|Name=Case Code (Metric)
|RECORD=41|OwnerIndex=206|IndexInSheet=23|OwnerPartId=-1|Location.X=529|Location.Y=732|Color=8388608|FontID=1|IsHidden=T|Text=1206|Name=Case Code (Imperial)
|RECORD=41|OwnerIndex=206|IndexInSheet=24|OwnerPartId=-1|Location.X=529|Location.Y=732|Color=8388608|FontID=1|IsHidden=T|Text=6.3V|Name=Voltage
|RECORD=41|OwnerIndex=206|IndexInSheet=25|OwnerPartId=-1|Location.X=529|Location.Y=732|Color=8388608|FontID=1|IsHidden=T|Text=6.3V|Name=Voltage Rating
|RECORD=41|OwnerIndex=206|IndexInSheet=26|OwnerPartId=-1|Location.X=529|Location.Y=732|Color=8388608|FontID=1|IsHidden=T|Text=47uF|Name=Capacitance
|RECORD=41|OwnerIndex=206|IndexInSheet=27|OwnerPartId=-1|Location.X=529|Location.Y=732|Color=8388608|FontID=1|IsHidden=T|Text=-55°C|Name=Min Operating Temperature
|RECORD=41|OwnerIndex=206|IndexInSheet=28|OwnerPartId=-1|Location.X=529|Location.Y=732|Color=8388608|FontID=1|IsHidden=T|Text=Ceramic|Name=Material
|RECORD=41|OwnerIndex=206|IndexInSheet=29|OwnerPartId=-1|Location.X=529|Location.Y=732|Color=8388608|FontID=1|IsHidden=T|Text=No SVHC|Name=REACH SVHC
|RECORD=34|OwnerIndex=206|IndexInSheet=-1|OwnerPartId=-1|Location.X=530|Location.Y=710|Orientation=1|Color=8388608|FontID=2|Text=C6|Name=Designator|ReadOnlyState=1
|RECORD=41|OwnerIndex=206|IndexInSheet=-1|OwnerPartId=1|Location.X=560|Location.Y=690|Orientation=1|Color=8388608|FontID=2|Text=47uF_6.3V_1206|Name=Comment
|RECORD=44|OwnerIndex=206
|RECORD=45|OwnerIndex=241|IndexInSheet=-1|UseComponentLibrary=T|ModelName=FP-GRM31C-0_2-e0_3_0_8-IPC_C|ModelType=PCBLIB|DatafileCount=1|ModelDatafileEntity0=FP-GRM31C-0_2-e0_3_0_8-IPC_C|ModelDatafileKind0=PCBLib|IsCurrent=T|DatalinksLocked=T|DatabaseDatalinksLocked=T
|RECORD=46|OwnerIndex=242
|RECORD=48|OwnerIndex=242
|RECORD=45|OwnerIndex=241|IndexInSheet=-1|UseComponentLibrary=T|ModelName=FP-GRM31C-0_2-e0_3_0_8-IPC_A|ModelType=PCBLIB|DatafileCount=1|ModelDatafileEntity0=FP-GRM31C-0_2-e0_3_0_8-IPC_A|ModelDatafileKind0=PCBLib|DatalinksLocked=T|DatabaseDatalinksLocked=T
|RECORD=46|OwnerIndex=245
|RECORD=48|OwnerIndex=245
|RECORD=45|OwnerIndex=241|IndexInSheet=-1|UseComponentLibrary=T|ModelName=FP-GRM31C-0_2-e0_3_0_8-IPC_B|ModelType=PCBLIB|DatafileCount=1|ModelDatafileEntity0=FP-GRM31C-0_2-e0_3_0_8-IPC_B|ModelDatafileKind0=PCBLib|DatalinksLocked=T|DatabaseDatalinksLocked=T
|RECORD=46|OwnerIndex=248
|RECORD=48|OwnerIndex=248
|RECORD=45|OwnerIndex=241|IndexInSheet=-1|UseComponentLibrary=T|ModelName=FP-GRM31C-0_2-e0_3_0_8-MFG|ModelType=PCBLIB|DatafileCount=1|ModelDatafileEntity0=FP-GRM31C-0_2-e0_3_0_8-MFG|ModelDatafileKind0=PCBLib|DatalinksLocked=T|DatabaseDatalinksLocked=T
|RECORD=46|OwnerIndex=251
|RECORD=48|OwnerIndex=251
|RECORD=1|LibReference=02cd4be3c70576c341d710602a673aa|ComponentDescription=Chip Multilayer Ceramic Capacitors for General Purpose, 1206, 47uF, X5R, 15%, 20%, 6.3V|PartCount=2|DisplayModeCount=1|IndexInSheet=65|OwnerPartId=-1|Location.X=580|Location.Y=730|CurrentPartId=1|LibraryPath=*|SourceLibraryName=Altium Content Vault|TargetFileName=*|AreaColor=11599871|Color=128|PartIDLocked=T|DesignItemId=CMP-2000-06344-2|AllPinCount=2
|RECORD=2|OwnerIndex=254|OwnerPartId=1|Electrical=4|PinConglomerate=49|PinLength=7|Location.X=580|Location.Y=723|Name=1|Designator=1|PinPropagationDelay=0.000000E+000
|RECORD=2|OwnerIndex=254|OwnerPartId=1|Electrical=4|PinConglomerate=51|PinLength=6|Location.X=580|Location.Y=716|Name=2|Designator=2|PinPropagationDelay=0.000000E+000
|RECORD=13|OwnerIndex=254|IsNotAccesible=T|IndexInSheet=2|OwnerPartId=1|Location.X=590|Location.Y=723|Corner.X=570|Corner.Y=723|LineWidth=1|Color=16711680
|RECORD=13|OwnerIndex=254|IsNotAccesible=T|IndexInSheet=3|OwnerPartId=1|Location.X=590|Location.Y=717|Corner.X=570|Corner.Y=717|LineWidth=1|Color=16711680
|RECORD=13|OwnerIndex=254|IsNotAccesible=T|IndexInSheet=4|OwnerPartId=1|Location.X=580|Location.Y=723|Corner.X=580|Corner.Y=726|LineWidth=1|Color=16711680
|RECORD=13|OwnerIndex=254|IsNotAccesible=T|IndexInSheet=5|OwnerPartId=1|Location.X=580|Location.Y=716|Corner.X=580|Corner.Y=715|LineWidth=1|Color=16711680
|RECORD=41|OwnerIndex=254|IndexInSheet=6|OwnerPartId=-1|Location.X=569|Location.Y=732|Color=8388608|FontID=1|IsHidden=T|Text=2000|Name=Package Quantity
|RECORD=41|OwnerIndex=254|IndexInSheet=7|OwnerPartId=-1|Location.X=569|Location.Y=732|Color=8388608|FontID=1|IsHidden=T|Text=Surface Mount|Name=Mount
|RECORD=41|OwnerIndex=254|IndexInSheet=8|OwnerPartId=-1|Location.X=569|Location.Y=732|Color=8388608|FontID=1|IsHidden=T|Text=3.2mm|Name=Length
|RECORD=41|OwnerIndex=254|IndexInSheet=9|OwnerPartId=-1|Location.X=569|Location.Y=732|Color=8388608|FontID=1|IsHidden=T|Text=0.071inch|Name=Thickness
|RECORD=41|OwnerIndex=254|IndexInSheet=10|OwnerPartId=-1|Location.X=569|Location.Y=732|Color=8388608|FontID=1|IsHidden=T|Text=Lead Free|Name=Lead Free
|RECORD=41|OwnerIndex=254|IndexInSheet=11|OwnerPartId=-1|Location.X=569|Location.Y=732|Color=8388608|FontID=1|IsHidden=T|Text=20%|Name=Tolerance
|RECORD=41|OwnerIndex=254|IndexInSheet=12|OwnerPartId=-1|Location.X=569|Location.Y=732|Color=8388608|FontID=1|IsHidden=T|Text=0.063inch|Name=Width
|RECORD=41|OwnerIndex=254|IndexInSheet=13|OwnerPartId=-1|Location.X=569|Location.Y=732|Color=8388608|FontID=1|IsHidden=T|Text=1.6mm|Name=Depth
|RECORD=41|OwnerIndex=254|IndexInSheet=14|OwnerPartId=-1|Location.X=569|Location.Y=732|Color=8388608|FontID=1|IsHidden=T|Text=1206|Name=Case/Package
|RECORD=41|OwnerIndex=254|IndexInSheet=15|OwnerPartId=-1|Location.X=569|Location.Y=732|Color=8388608|FontID=1|IsHidden=T|Text=X5R|Name=Dielectric
|RECORD=41|OwnerIndex=254|IndexInSheet=16|OwnerPartId=-1|Location.X=569|Location.Y=732|Color=8388608|FontID=1|IsHidden=T|Text=No|Name=Radiation Hardening
|RECORD=41|OwnerIndex=254|IndexInSheet=17|OwnerPartId=-1|Location.X=569|Location.Y=732|Color=8388608|FontID=1|IsHidden=T|Text=Tape and Reel|Name=Packaging
|RECORD=41|OwnerIndex=254|IndexInSheet=18|OwnerPartId=-1|Location.X=569|Location.Y=732|Color=8388608|FontID=1|IsHidden=T|Text=6.3V|Name=Voltage Rating (DC)
|RECORD=41|OwnerIndex=254|IndexInSheet=19|OwnerPartId=-1|Location.X=569|Location.Y=732|Color=8388608|FontID=1|IsHidden=T|Text=SMD/SMT|Name=Termination
|RECORD=41|OwnerIndex=254|IndexInSheet=20|OwnerPartId=-1|Location.X=569|Location.Y=732|Color=8388608|FontID=1|IsHidden=T|Text=1.6mm|Name=Height
|RECORD=41|OwnerIndex=254|IndexInSheet=21|OwnerPartId=-1|Location.X=569|Location.Y=732|Color=8388608|FontID=1|IsHidden=T|Text=85°C|Name=Max Operating Temperature
|RECORD=41|OwnerIndex=254|IndexInSheet=22|OwnerPartId=-1|Location.X=569|Location.Y=732|Color=8388608|FontID=1|IsHidden=T|Text=3216|Name=Case Code (Metric)
|RECORD=41|OwnerIndex=254|IndexInSheet=23|OwnerPartId=-1|Location.X=569|Location.Y=732|Color=8388608|FontID=1|IsHidden=T|Text=1206|Name=Case Code (Imperial)
|RECORD=41|OwnerIndex=254|IndexInSheet=24|OwnerPartId=-1|Location.X=569|Location.Y=732|Color=8388608|FontID=1|IsHidden=T|Text=6.3V|Name=Voltage
|RECORD=41|OwnerIndex=254|IndexInSheet=25|OwnerPartId=-1|Location.X=569|Location.Y=732|Color=8388608|FontID=1|IsHidden=T|Text=6.3V|Name=Voltage Rating
|RECORD=41|OwnerIndex=254|IndexInSheet=26|OwnerPartId=-1|Location.X=569|Location.Y=732|Color=8388608|FontID=1|IsHidden=T|Text=47uF|Name=Capacitance
|RECORD=41|OwnerIndex=254|IndexInSheet=27|OwnerPartId=-1|Location.X=569|Location.Y=732|Color=8388608|FontID=1|IsHidden=T|Text=-55°C|Name=Min Operating Temperature
|RECORD=41|OwnerIndex=254|IndexInSheet=28|OwnerPartId=-1|Location.X=569|Location.Y=732|Color=8388608|FontID=1|IsHidden=T|Text=Ceramic|Name=Material
|RECORD=41|OwnerIndex=254|IndexInSheet=29|OwnerPartId=-1|Location.X=569|Location.Y=732|Color=8388608|FontID=1|IsHidden=T|Text=No SVHC|Name=REACH SVHC
|RECORD=34|OwnerIndex=254|IndexInSheet=-1|OwnerPartId=-1|Location.X=570|Location.Y=710|Orientation=1|Color=8388608|FontID=2|Text=C7|Name=Designator|ReadOnlyState=1
|RECORD=41|OwnerIndex=254|IndexInSheet=-1|OwnerPartId=1|Location.X=600|Location.Y=690|Orientation=1|Color=8388608|FontID=2|Text=47uF_6.3V_1206|Name=Comment
|RECORD=44|OwnerIndex=254
|RECORD=45|OwnerIndex=289|IndexInSheet=-1|UseComponentLibrary=T|ModelName=FP-GRM31C-0_2-e0_3_0_8-IPC_C|ModelType=PCBLIB|DatafileCount=1|ModelDatafileEntity0=FP-GRM31C-0_2-e0_3_0_8-IPC_C|ModelDatafileKind0=PCBLib|IsCurrent=T|DatalinksLocked=T|DatabaseDatalinksLocked=T
|RECORD=46|OwnerIndex=290
|RECORD=48|OwnerIndex=290
|RECORD=45|OwnerIndex=289|IndexInSheet=-1|UseComponentLibrary=T|ModelName=FP-GRM31C-0_2-e0_3_0_8-IPC_A|ModelType=PCBLIB|DatafileCount=1|ModelDatafileEntity0=FP-GRM31C-0_2-e0_3_0_8-IPC_A|ModelDatafileKind0=PCBLib|DatalinksLocked=T|DatabaseDatalinksLocked=T
|RECORD=46|OwnerIndex=293
|RECORD=48|OwnerIndex=293
|RECORD=45|OwnerIndex=289|IndexInSheet=-1|UseComponentLibrary=T|ModelName=FP-GRM31C-0_2-e0_3_0_8-IPC_B|ModelType=PCBLIB|DatafileCount=1|ModelDatafileEntity0=FP-GRM31C-0_2-e0_3_0_8-IPC_B|ModelDatafileKind0=PCBLib|DatalinksLocked=T|DatabaseDatalinksLocked=T
|RECORD=46|OwnerIndex=296
|RECORD=48|OwnerIndex=296
|RECORD=45|OwnerIndex=289|IndexInSheet=-1|UseComponentLibrary=T|ModelName=FP-GRM31C-0_2-e0_3_0_8-MFG|ModelType=PCBLIB|DatafileCount=1|ModelDatafileEntity0=FP-GRM31C-0_2-e0_3_0_8-MFG|ModelDatafileKind0=PCBLib|DatalinksLocked=T|DatabaseDatalinksLocked=T
|RECORD=46|OwnerIndex=299
|RECORD=48|OwnerIndex=299
|RECORD=27|IndexInSheet=66|OwnerPartId=-1|LineWidth=1|Color=8388608|LocationCount=8|X1=680|Y1=670|X2=660|Y2=670|X3=660|Y3=680|X4=660|Y4=690|X5=660|Y5=700|X6=660|Y6=710|X7=660|Y7=760|X8=660|Y8=770
|RECORD=27|IndexInSheet=67|OwnerPartId=-1|LineWidth=1|Color=8388608|LocationCount=4|X1=660|Y1=760|X2=580|Y2=760|X3=540|Y3=760|X4=540|Y4=730
|RECORD=27|IndexInSheet=68|OwnerPartId=-1|LineWidth=1|Color=8388608|LocationCount=2|X1=580|Y1=730|X2=580|Y2=760
|RECORD=17|IndexInSheet=69|OwnerPartId=-1|Style=4|ShowNetName=F|Location.X=540|Location.Y=680|Orientation=3|Color=128|FontID=1|Text=GND
|RECORD=27|IndexInSheet=70|OwnerPartId=-1|LineWidth=1|Color=8388608|LocationCount=3|X1=540|Y1=680|X2=540|Y2=690|X3=540|Y3=710
|RECORD=27|IndexInSheet=71|OwnerPartId=-1|LineWidth=1|Color=8388608|LocationCount=3|X1=580|Y1=710|X2=580|Y2=690|X3=540|Y3=690
|RECORD=1|LibReference=RES|PartCount=2|DisplayModeCount=2|IndexInSheet=72|OwnerPartId=-1|Location.X=580|Location.Y=680|CurrentPartId=1|SourceLibraryName=Altium Content Vault|TargetFileName=*|AreaColor=11599871|Color=128|PartIDLocked=F|DesignItemId=CMP-2002-06457-1|AllPinCount=2
|RECORD=2|OwnerIndex=308|OwnerPartId=1|OwnerPartDisplayMode=1|FormalType=1|Electrical=4|PinConglomerate=32|PinLength=10|Location.X=600|Location.Y=670|Name=2|Designator=2|PinPropagationDelay=0.000000E+000
|RECORD=2|OwnerIndex=308|OwnerPartId=1|OwnerPartDisplayMode=1|FormalType=1|Electrical=4|PinConglomerate=34|PinLength=10|Location.X=580|Location.Y=670|Name=1|Designator=1|PinPropagationDelay=0.000000E+000
|RECORD=14|OwnerIndex=308|IsNotAccesible=T|IndexInSheet=2|OwnerPartId=1|OwnerPartDisplayMode=1|Location.X=580|Location.Y=666|Corner.X=600|Corner.Y=674|LineWidth=1|Color=16711680|AreaColor=11599871
|RECORD=2|OwnerIndex=308|OwnerPartId=1|FormalType=1|Electrical=4|PinConglomerate=32|PinLength=10|Location.X=600|Location.Y=670|Name=2|Designator=2|PinPropagationDelay=0.000000E+000
|RECORD=2|OwnerIndex=308|OwnerPartId=1|FormalType=1|Electrical=4|PinConglomerate=34|PinLength=10|Location.X=580|Location.Y=670|Name=1|Designator=1|PinPropagationDelay=0.000000E+000
|RECORD=6|OwnerIndex=308|IsNotAccesible=T|IndexInSheet=5|OwnerPartId=1|LineWidth=1|Color=16711680|LocationCount=10|X1=600|Y1=670|X2=596|Y2=670|X3=595|Y3=668|X4=593|Y4=672|X5=591|Y5=668|X6=589|Y6=672|X7=587|Y7=668|X8=585|Y8=672|X9=584|Y9=670|X10=580|Y10=670
|RECORD=41|OwnerIndex=308|IndexInSheet=6|OwnerPartId=-1|Location.X=568|Location.Y=683|Color=8388608|FontID=1|IsHidden=T|Text=Panasonic|Name=Manufacturer
|RECORD=41|OwnerIndex=308|IndexInSheet=7|OwnerPartId=-1|Location.X=568|Location.Y=683|Color=8388608|FontID=1|IsHidden=T|Text=ERJ-U020R00X|Name=Part Number
|RECORD=34|OwnerIndex=308|IndexInSheet=-1|OwnerPartId=-1|Location.X=579|Location.Y=673|Color=8388608|FontID=1|Text=R12|Name=Designator|ReadOnlyState=1
|RECORD=41|OwnerIndex=308|IndexInSheet=-1|OwnerPartId=-1|Location.X=579|Location.Y=657|Color=8388608|FontID=1|Text=0_5%_0402|Name=Comment
|RECORD=44|OwnerIndex=308
|RECORD=45|OwnerIndex=323|IndexInSheet=-1|Description=Chip Resistor, 2-Leads, Body 1.00x0.50mm, IPC Medium Density|UseComponentLibrary=T|ModelName=RESC1005X40X25NL05T10|ModelType=PCBLIB|DatafileCount=1|ModelDatafileEntity0=RESC1005X40X25NL05T10|ModelDatafileKind0=PCBLib|IsCurrent=T|DatalinksLocked=T|DatabaseDatalinksLocked=T
|RECORD=46|OwnerIndex=324
|RECORD=48|OwnerIndex=324
|RECORD=41|OwnerIndex=326|IndexInSheet=-1|OwnerPartId=-1|Color=8388608|FontID=1|IsHidden=T|Text=2D|Name=Available Preview Images
|RECORD=45|OwnerIndex=323|IndexInSheet=-1|Description=Chip Resistor, 2-Leads, Body 1.00x0.50mm, IPC High Density|UseComponentLibrary=T|ModelName=RESC1005X40X25LL05T10|ModelType=PCBLIB|DatafileCount=1|ModelDatafileEntity0=RESC1005X40X25LL05T10|ModelDatafileKind0=PCBLib|DatalinksLocked=T|DatabaseDatalinksLocked=T
|RECORD=46|OwnerIndex=328
|RECORD=48|OwnerIndex=328
|RECORD=41|OwnerIndex=330|IndexInSheet=-1|OwnerPartId=-1|Color=8388608|FontID=1|IsHidden=T|Text=2D|Name=Available Preview Images
|RECORD=45|OwnerIndex=323|IndexInSheet=-1|Description=Chip Resistor, 2-Leads, Body 1.00x0.50mm, IPC Low Density|UseComponentLibrary=T|ModelName=RESC1005X40X25ML05T10|ModelType=PCBLIB|DatafileCount=1|ModelDatafileEntity0=RESC1005X40X25ML05T10|ModelDatafileKind0=PCBLib|DatalinksLocked=T|DatabaseDatalinksLocked=T
|RECORD=46|OwnerIndex=332
|RECORD=48|OwnerIndex=332
|RECORD=41|OwnerIndex=334|IndexInSheet=-1|OwnerPartId=-1|Color=8388608|FontID=1|IsHidden=T|Text=2D|Name=Available Preview Images
|RECORD=1|LibReference=RES|PartCount=2|DisplayModeCount=2|IndexInSheet=73|OwnerPartId=-1|Location.X=580|Location.Y=650|CurrentPartId=1|SourceLibraryName=Altium Content Vault|TargetFileName=*|AreaColor=11599871|Color=128|PartIDLocked=F|DesignItemId=CMP-2002-06457-1|AllPinCount=2
|RECORD=2|OwnerIndex=336|OwnerPartId=1|OwnerPartDisplayMode=1|FormalType=1|Electrical=4|PinConglomerate=32|PinLength=10|Location.X=600|Location.Y=640|Name=2|Designator=2|PinPropagationDelay=0.000000E+000
|RECORD=2|OwnerIndex=336|OwnerPartId=1|OwnerPartDisplayMode=1|FormalType=1|Electrical=4|PinConglomerate=34|PinLength=10|Location.X=580|Location.Y=640|Name=1|Designator=1|PinPropagationDelay=0.000000E+000
|RECORD=14|OwnerIndex=336|IsNotAccesible=T|IndexInSheet=2|OwnerPartId=1|OwnerPartDisplayMode=1|Location.X=580|Location.Y=636|Corner.X=600|Corner.Y=644|LineWidth=1|Color=16711680|AreaColor=11599871
|RECORD=2|OwnerIndex=336|OwnerPartId=1|FormalType=1|Electrical=4|PinConglomerate=32|PinLength=10|Location.X=600|Location.Y=640|Name=2|Designator=2|PinPropagationDelay=0.000000E+000
|RECORD=2|OwnerIndex=336|OwnerPartId=1|FormalType=1|Electrical=4|PinConglomerate=34|PinLength=10|Location.X=580|Location.Y=640|Name=1|Designator=1|PinPropagationDelay=0.000000E+000
|RECORD=6|OwnerIndex=336|IsNotAccesible=T|IndexInSheet=5|OwnerPartId=1|LineWidth=1|Color=16711680|LocationCount=10|X1=600|Y1=640|X2=596|Y2=640|X3=595|Y3=638|X4=593|Y4=642|X5=591|Y5=638|X6=589|Y6=642|X7=587|Y7=638|X8=585|Y8=642|X9=584|Y9=640|X10=580|Y10=640
|RECORD=41|OwnerIndex=336|IndexInSheet=6|OwnerPartId=-1|Location.X=568|Location.Y=653|Color=8388608|FontID=1|IsHidden=T|Text=Panasonic|Name=Manufacturer
|RECORD=41|OwnerIndex=336|IndexInSheet=7|OwnerPartId=-1|Location.X=568|Location.Y=653|Color=8388608|FontID=1|IsHidden=T|Text=ERJ-U020R00X|Name=Part Number
|RECORD=34|OwnerIndex=336|IndexInSheet=-1|OwnerPartId=-1|Location.X=579|Location.Y=643|Color=8388608|FontID=1|Text=R13|Name=Designator|ReadOnlyState=1
|RECORD=41|OwnerIndex=336|IndexInSheet=-1|OwnerPartId=-1|Location.X=579|Location.Y=627|Color=8388608|FontID=1|Text=0_5%_0402|Name=Comment
|RECORD=44|OwnerIndex=336
|RECORD=45|OwnerIndex=351|IndexInSheet=-1|Description=Chip Resistor, 2-Leads, Body 1.00x0.50mm, IPC Medium Density|UseComponentLibrary=T|ModelName=RESC1005X40X25NL05T10|ModelType=PCBLIB|DatafileCount=1|ModelDatafileEntity0=RESC1005X40X25NL05T10|ModelDatafileKind0=PCBLib|IsCurrent=T|DatalinksLocked=T|DatabaseDatalinksLocked=T
|RECORD=46|OwnerIndex=352
|RECORD=48|OwnerIndex=352
|RECORD=41|OwnerIndex=354|IndexInSheet=-1|OwnerPartId=-1|Color=8388608|FontID=1|IsHidden=T|Text=2D|Name=Available Preview Images
|RECORD=45|OwnerIndex=351|IndexInSheet=-1|Description=Chip Resistor, 2-Leads, Body 1.00x0.50mm, IPC High Density|UseComponentLibrary=T|ModelName=RESC1005X40X25LL05T10|ModelType=PCBLIB|DatafileCount=1|ModelDatafileEntity0=RESC1005X40X25LL05T10|ModelDatafileKind0=PCBLib|DatalinksLocked=T|DatabaseDatalinksLocked=T
|RECORD=46|OwnerIndex=356
|RECORD=48|OwnerIndex=356
|RECORD=41|OwnerIndex=358|IndexInSheet=-1|OwnerPartId=-1|Color=8388608|FontID=1|IsHidden=T|Text=2D|Name=Available Preview Images
|RECORD=45|OwnerIndex=351|IndexInSheet=-1|Description=Chip Resistor, 2-Leads, Body 1.00x0.50mm, IPC Low Density|UseComponentLibrary=T|ModelName=RESC1005X40X25ML05T10|ModelType=PCBLIB|DatafileCount=1|ModelDatafileEntity0=RESC1005X40X25ML05T10|ModelDatafileKind0=PCBLib|DatalinksLocked=T|DatabaseDatalinksLocked=T
|RECORD=46|OwnerIndex=360
|RECORD=48|OwnerIndex=360
|RECORD=41|OwnerIndex=362|IndexInSheet=-1|OwnerPartId=-1|Color=8388608|FontID=1|IsHidden=T|Text=2D|Name=Available Preview Images
|RECORD=1|LibReference=RES|PartCount=2|DisplayModeCount=2|IndexInSheet=74|OwnerPartId=-1|Location.X=960|Location.Y=640|CurrentPartId=1|SourceLibraryName=Altium Content Vault|TargetFileName=*|AreaColor=11599871|Color=128|PartIDLocked=F|DesignItemId=CMP-2002-06457-1|AllPinCount=2|ComponentKindVersion2=5
|RECORD=2|OwnerIndex=364|OwnerPartId=1|OwnerPartDisplayMode=1|FormalType=1|Electrical=4|PinConglomerate=32|PinLength=10|Location.X=980|Location.Y=630|Name=2|Designator=2|PinPropagationDelay=0.000000E+000
|RECORD=2|OwnerIndex=364|OwnerPartId=1|OwnerPartDisplayMode=1|FormalType=1|Electrical=4|PinConglomerate=34|PinLength=10|Location.X=960|Location.Y=630|Name=1|Designator=1|PinPropagationDelay=0.000000E+000
|RECORD=14|OwnerIndex=364|IsNotAccesible=T|IndexInSheet=2|OwnerPartId=1|OwnerPartDisplayMode=1|Location.X=960|Location.Y=626|Corner.X=980|Corner.Y=634|LineWidth=1|Color=16711680|AreaColor=11599871
|RECORD=2|OwnerIndex=364|OwnerPartId=1|FormalType=1|Electrical=4|PinConglomerate=32|PinLength=10|Location.X=980|Location.Y=630|Name=2|Designator=2|PinPropagationDelay=0.000000E+000
|RECORD=2|OwnerIndex=364|OwnerPartId=1|FormalType=1|Electrical=4|PinConglomerate=34|PinLength=10|Location.X=960|Location.Y=630|Name=1|Designator=1|PinPropagationDelay=0.000000E+000
|RECORD=6|OwnerIndex=364|IsNotAccesible=T|IndexInSheet=5|OwnerPartId=1|LineWidth=1|Color=16711680|LocationCount=10|X1=980|Y1=630|X2=976|Y2=630|X3=975|Y3=628|X4=973|Y4=632|X5=971|Y5=628|X6=969|Y6=632|X7=967|Y7=628|X8=965|Y8=632|X9=964|Y9=630|X10=960|Y10=630
|RECORD=41|OwnerIndex=364|IndexInSheet=6|OwnerPartId=-1|Location.X=948|Location.Y=643|Color=8388608|FontID=1|IsHidden=T|Text=Panasonic|Name=Manufacturer
|RECORD=41|OwnerIndex=364|IndexInSheet=7|OwnerPartId=-1|Location.X=948|Location.Y=643|Color=8388608|FontID=1|IsHidden=T|Text=ERJ-U020R00X|Name=Part Number
|RECORD=34|OwnerIndex=364|IndexInSheet=-1|OwnerPartId=-1|Location.X=940|Location.Y=630|Color=8388608|FontID=1|Text=R14|Name=Designator|ReadOnlyState=1
|RECORD=41|OwnerIndex=364|IndexInSheet=-1|OwnerPartId=-1|Location.X=980|Location.Y=630|Color=8388608|FontID=1|Text=DNI_0_5%_0402|Name=Comment
|RECORD=44|OwnerIndex=364
|RECORD=45|OwnerIndex=379|IndexInSheet=-1|Description=Chip Resistor, 2-Leads, Body 1.00x0.50mm, IPC Medium Density|UseComponentLibrary=T|ModelName=RESC1005X40X25NL05T10|ModelType=PCBLIB|DatafileCount=1|ModelDatafileEntity0=RESC1005X40X25NL05T10|ModelDatafileKind0=PCBLib|IsCurrent=T|DatalinksLocked=T|DatabaseDatalinksLocked=T
|RECORD=46|OwnerIndex=380
|RECORD=48|OwnerIndex=380
|RECORD=41|OwnerIndex=382|IndexInSheet=-1|OwnerPartId=-1|Color=8388608|FontID=1|IsHidden=T|Text=2D|Name=Available Preview Images
|RECORD=45|OwnerIndex=379|IndexInSheet=-1|Description=Chip Resistor, 2-Leads, Body 1.00x0.50mm, IPC High Density|UseComponentLibrary=T|ModelName=RESC1005X40X25LL05T10|ModelType=PCBLIB|DatafileCount=1|ModelDatafileEntity0=RESC1005X40X25LL05T10|ModelDatafileKind0=PCBLib|DatalinksLocked=T|DatabaseDatalinksLocked=T
|RECORD=46|OwnerIndex=384
|RECORD=48|OwnerIndex=384
|RECORD=41|OwnerIndex=386|IndexInSheet=-1|OwnerPartId=-1|Color=8388608|FontID=1|IsHidden=T|Text=2D|Name=Available Preview Images
|RECORD=45|OwnerIndex=379|IndexInSheet=-1|Description=Chip Resistor, 2-Leads, Body 1.00x0.50mm, IPC Low Density|UseComponentLibrary=T|ModelName=RESC1005X40X25ML05T10|ModelType=PCBLIB|DatafileCount=1|ModelDatafileEntity0=RESC1005X40X25ML05T10|ModelDatafileKind0=PCBLib|DatalinksLocked=T|DatabaseDatalinksLocked=T
|RECORD=46|OwnerIndex=388
|RECORD=48|OwnerIndex=388
|RECORD=41|OwnerIndex=390|IndexInSheet=-1|OwnerPartId=-1|Color=8388608|FontID=1|IsHidden=T|Text=2D|Name=Available Preview Images
|RECORD=1|LibReference=RES|PartCount=2|DisplayModeCount=2|IndexInSheet=75|OwnerPartId=-1|Location.X=960|Location.Y=630|CurrentPartId=1|SourceLibraryName=Altium Content Vault|TargetFileName=*|AreaColor=11599871|Color=128|PartIDLocked=F|DesignItemId=CMP-2002-06457-1|AllPinCount=2
|RECORD=2|OwnerIndex=392|OwnerPartId=1|OwnerPartDisplayMode=1|FormalType=1|Electrical=4|PinConglomerate=32|PinLength=10|Location.X=980|Location.Y=620|Name=2|Designator=2|PinPropagationDelay=0.000000E+000
|RECORD=2|OwnerIndex=392|OwnerPartId=1|OwnerPartDisplayMode=1|FormalType=1|Electrical=4|PinConglomerate=34|PinLength=10|Location.X=960|Location.Y=620|Name=1|Designator=1|PinPropagationDelay=0.000000E+000
|RECORD=14|OwnerIndex=392|IsNotAccesible=T|IndexInSheet=2|OwnerPartId=1|OwnerPartDisplayMode=1|Location.X=960|Location.Y=616|Corner.X=980|Corner.Y=624|LineWidth=1|Color=16711680|AreaColor=11599871
|RECORD=2|OwnerIndex=392|OwnerPartId=1|FormalType=1|Electrical=4|PinConglomerate=32|PinLength=10|Location.X=980|Location.Y=620|Name=2|Designator=2|PinPropagationDelay=0.000000E+000
|RECORD=2|OwnerIndex=392|OwnerPartId=1|FormalType=1|Electrical=4|PinConglomerate=34|PinLength=10|Location.X=960|Location.Y=620|Name=1|Designator=1|PinPropagationDelay=0.000000E+000
|RECORD=6|OwnerIndex=392|IsNotAccesible=T|IndexInSheet=5|OwnerPartId=1|LineWidth=1|Color=16711680|LocationCount=10|X1=980|Y1=620|X2=976|Y2=620|X3=975|Y3=618|X4=973|Y4=622|X5=971|Y5=618|X6=969|Y6=622|X7=967|Y7=618|X8=965|Y8=622|X9=964|Y9=620|X10=960|Y10=620
|RECORD=41|OwnerIndex=392|IndexInSheet=6|OwnerPartId=-1|Location.X=948|Location.Y=633|Color=8388608|FontID=1|IsHidden=T|Text=Panasonic|Name=Manufacturer
|RECORD=41|OwnerIndex=392|IndexInSheet=7|OwnerPartId=-1|Location.X=948|Location.Y=633|Color=8388608|FontID=1|IsHidden=T|Text=ERJ-U020R00X|Name=Part Number
|RECORD=34|OwnerIndex=392|IndexInSheet=-1|OwnerPartId=-1|Location.X=940|Location.Y=620|Color=8388608|FontID=1|Text=R15|Name=Designator|ReadOnlyState=1
|RECORD=41|OwnerIndex=392|IndexInSheet=-1|OwnerPartId=-1|Location.X=980|Location.Y=620|Color=8388608|FontID=1|Text=0_5%_0402|Name=Comment
|RECORD=44|OwnerIndex=392
|RECORD=45|OwnerIndex=407|IndexInSheet=-1|Description=Chip Resistor, 2-Leads, Body 1.00x0.50mm, IPC Medium Density|UseComponentLibrary=T|ModelName=RESC1005X40X25NL05T10|ModelType=PCBLIB|DatafileCount=1|ModelDatafileEntity0=RESC1005X40X25NL05T10|ModelDatafileKind0=PCBLib|IsCurrent=T|DatalinksLocked=T|DatabaseDatalinksLocked=T
|RECORD=46|OwnerIndex=408
|RECORD=48|OwnerIndex=408
|RECORD=41|OwnerIndex=410|IndexInSheet=-1|OwnerPartId=-1|Color=8388608|FontID=1|IsHidden=T|Text=2D|Name=Available Preview Images
|RECORD=45|OwnerIndex=407|IndexInSheet=-1|Description=Chip Resistor, 2-Leads, Body 1.00x0.50mm, IPC High Density|UseComponentLibrary=T|ModelName=RESC1005X40X25LL05T10|ModelType=PCBLIB|DatafileCount=1|ModelDatafileEntity0=RESC1005X40X25LL05T10|ModelDatafileKind0=PCBLib|DatalinksLocked=T|DatabaseDatalinksLocked=T
|RECORD=46|OwnerIndex=412
|RECORD=48|OwnerIndex=412
|RECORD=41|OwnerIndex=414|IndexInSheet=-1|OwnerPartId=-1|Color=8388608|FontID=1|IsHidden=T|Text=2D|Name=Available Preview Images
|RECORD=45|OwnerIndex=407|IndexInSheet=-1|Description=Chip Resistor, 2-Leads, Body 1.00x0.50mm, IPC Low Density|UseComponentLibrary=T|ModelName=RESC1005X40X25ML05T10|ModelType=PCBLIB|DatafileCount=1|ModelDatafileEntity0=RESC1005X40X25ML05T10|ModelDatafileKind0=PCBLib|DatalinksLocked=T|DatabaseDatalinksLocked=T
|RECORD=46|OwnerIndex=416
|RECORD=48|OwnerIndex=416
|RECORD=41|OwnerIndex=418|IndexInSheet=-1|OwnerPartId=-1|Color=8388608|FontID=1|IsHidden=T|Text=2D|Name=Available Preview Images
|RECORD=17|IndexInSheet=76|OwnerPartId=-1|ShowNetName=T|Location.X=1050|Location.Y=620|Color=255|FontID=1|Text=TP1|IsCrossSheetConnector=T
|RECORD=27|IndexInSheet=77|OwnerPartId=-1|LineWidth=1|Color=8388608|LocationCount=4|X1=1050|Y1=620|X2=1030|Y2=620|X3=1030|Y3=630|X4=990|Y4=630
|RECORD=27|IndexInSheet=78|OwnerPartId=-1|LineWidth=1|Color=8388608|LocationCount=2|X1=1030|Y1=620|X2=990|Y2=620
|RECORD=27|IndexInSheet=79|OwnerPartId=-1|LineWidth=1|Color=8388608|LocationCount=2|X1=950|Y1=630|X2=890|Y2=630
|RECORD=27|IndexInSheet=80|OwnerPartId=-1|LineWidth=1|Color=8388608|LocationCount=2|X1=890|Y1=620|X2=950|Y2=620
|RECORD=29|IndexInSheet=-1|OwnerPartId=-1|Location.X=540|Location.Y=690|Color=128
|RECORD=29|IndexInSheet=-1|OwnerPartId=-1|Location.X=560|Location.Y=650|Color=128
|RECORD=29|IndexInSheet=-1|OwnerPartId=-1|Location.X=580|Location.Y=760|Color=128
|RECORD=29|IndexInSheet=-1|OwnerPartId=-1|Location.X=660|Location.Y=340|Color=128
|RECORD=29|IndexInSheet=-1|OwnerPartId=-1|Location.X=660|Location.Y=350|Color=128
|RECORD=29|IndexInSheet=-1|OwnerPartId=-1|Location.X=660|Location.Y=360|Color=128
|RECORD=29|IndexInSheet=-1|OwnerPartId=-1|Location.X=660|Location.Y=370|Color=128
|RECORD=29|IndexInSheet=-1|OwnerPartId=-1|Location.X=660|Location.Y=380|Color=128
|RECORD=29|IndexInSheet=-1|OwnerPartId=-1|Location.X=660|Location.Y=390|Color=128
|RECORD=29|IndexInSheet=-1|OwnerPartId=-1|Location.X=660|Location.Y=400|Color=128
|RECORD=29|IndexInSheet=-1|OwnerPartId=-1|Location.X=660|Location.Y=410|Color=128
|RECORD=29|IndexInSheet=-1|OwnerPartId=-1|Location.X=660|Location.Y=420|Color=128
|RECORD=29|IndexInSheet=-1|OwnerPartId=-1|Location.X=660|Location.Y=430|Color=128
|RECORD=29|IndexInSheet=-1|OwnerPartId=-1|Location.X=660|Location.Y=490|Color=128
|RECORD=29|IndexInSheet=-1|OwnerPartId=-1|Location.X=660|Location.Y=510|Color=128
|RECORD=29|IndexInSheet=-1|OwnerPartId=-1|Location.X=660|Location.Y=680|Color=128
|RECORD=29|IndexInSheet=-1|OwnerPartId=-1|Location.X=660|Location.Y=690|Color=128
|RECORD=29|IndexInSheet=-1|OwnerPartId=-1|Location.X=660|Location.Y=700|Color=128
|RECORD=29|IndexInSheet=-1|OwnerPartId=-1|Location.X=660|Location.Y=710|Color=128
|RECORD=29|IndexInSheet=-1|OwnerPartId=-1|Location.X=660|Location.Y=760|Color=128
|RECORD=29|IndexInSheet=-1|OwnerPartId=-1|Location.X=1030|Location.Y=620|Color=128